(kicad_pcb
	(version 20241229)
	(generator "pcbnew")
	(generator_version "9.0")
	(general
		(thickness 1.599998)
		(legacy_teardrops no)
	)
	(paper "A4")
	(title_block
		(title "Artix - Datacenter Secure Control Module (DC-SCM)")
		(date "2024-11-06")
		(rev "1.1.3")
		(comment 9 "footprints 539-544 of 544")
	)
	(layers
		(0 "F.Cu" signal)
		(4 "In1.Cu" signal)
		(6 "In2.Cu" signal)
		(8 "In3.Cu" signal)
		(10 "In4.Cu" signal)
		(12 "In5.Cu" signal)
		(14 "In6.Cu" signal)
		(2 "B.Cu" signal)
		(9 "F.Adhes" user "F.Adhesive")
		(11 "B.Adhes" user "B.Adhesive")
		(13 "F.Paste" user)
		(15 "B.Paste" user)
		(5 "F.SilkS" user "F.Silkscreen")
		(7 "B.SilkS" user "B.Silkscreen")
		(1 "F.Mask" user)
		(3 "B.Mask" user)
		(17 "Dwgs.User" user "User.Drawings")
		(19 "Cmts.User" user "User.Comments")
		(21 "Eco1.User" user "User.Eco1")
		(23 "Eco2.User" user "User.Eco2")
		(25 "Edge.Cuts" user)
		(27 "Margin" user)
		(31 "F.CrtYd" user "F.Courtyard")
		(29 "B.CrtYd" user "B.Courtyard")
		(35 "F.Fab" user)
		(33 "B.Fab" user)
	)
	(footprint "antmicro-footprints:R_0402_1005Metric"
		(layer "B.Cu")
		(at 117.495 148.675)
		(descr "Resistor SMD 0402")
		(tags "resistor SMD 0402")
		(property "Reference" "R105"
			(at 0.805 0.425 0)
			(layer "B.SilkS")
			(effects
				(font
					(size 0.7 0.7)
					(thickness 0.15)
				)
				(justify right bottom mirror)
			)
		)
		(property "Value" "R_0R_0402"
			(at 0 -1.4 0)
			(layer "B.Fab")
			(effects
				(font
					(size 0.7 0.7)
					(thickness 0.15)
				)
				(justify right bottom mirror)
			)
		)
		(property "Datasheet" "https://industrial.panasonic.com/cdbs/www-data/pdf/RDA0000/AOA0000C301.pdf"
			(at 0 0 0)
			(layer "F.Fab")
			(hide yes)
			(effects
				(font
					(size 1.27 1.27)
					(thickness 0.15)
				)
			)
		)
		(property "Description" "SMD Chip Resistor, Jumper, 0 ohm, 100 mW, 0402 [1005 Metric], Thick Film, General Purpose"
			(at 0 0 0)
			(layer "F.Fab")
			(hide yes)
			(effects
				(font
					(size 1.27 1.27)
					(thickness 0.15)
				)
			)
		)
		(property "Author" "Antmicro"
			(at 0 0 0)
			(layer "B.Fab")
			(hide yes)
			(effects
				(font
					(size 1 1)
					(thickness 0.15)
				)
				(justify mirror)
			)
		)
		(property "Current" "1A"
			(at 0 0 0)
			(layer "B.Fab")
			(hide yes)
			(effects
				(font
					(size 1 1)
					(thickness 0.15)
				)
				(justify mirror)
			)
		)
		(property "License" "Apache-2.0"
			(at 0 0 0)
			(layer "B.Fab")
			(hide yes)
			(effects
				(font
					(size 1 1)
					(thickness 0.15)
				)
				(justify mirror)
			)
		)
		(property "MPN" "ERJ2GE0R00X"
			(at 0 0 0)
			(layer "B.Fab")
			(hide yes)
			(effects
				(font
					(size 1 1)
					(thickness 0.15)
				)
				(justify mirror)
			)
		)
		(property "Manufacturer" "Panasonic"
			(at 0 0 0)
			(layer "B.Fab")
			(hide yes)
			(effects
				(font
					(size 1 1)
					(thickness 0.15)
				)
				(justify mirror)
			)
		)
		(property "Tolerance" "~"
			(at 0 0 0)
			(layer "B.Fab")
			(hide yes)
			(effects
				(font
					(size 1 1)
					(thickness 0.15)
				)
				(justify mirror)
			)
		)
		(property "Val" "0R"
			(at 0 0 0)
			(layer "B.Fab")
			(hide yes)
			(effects
				(font
					(size 1 1)
					(thickness 0.15)
				)
				(justify mirror)
			)
		)
		(sheetname "/Edge connector/")
		(sheetfile "edge-connector.kicad_sch")
		(attr smd)
		(fp_rect
			(start -0.925 0.47)
			(end 0.925 -0.47)
			(stroke
				(width 0.05)
				(type default)
			)
			(fill no)
			(layer "B.CrtYd")
		)
		(fp_rect
			(start -0.5 0.25)
			(end 0.5 -0.25)
			(stroke
				(width 0.15)
				(type solid)
			)
			(fill no)
			(layer "B.Fab")
		)
		(pad "1" smd roundrect
			(at -0.48 0)
			(size 0.59 0.64)
			(layers "B.Cu" "B.Mask" "B.Paste")
			(roundrect_rratio 0.25)
			(net 391 "DBP_PREQ_N_R")
			(pintype "passive")
		)
		(pad "2" smd roundrect
			(at 0.48 0)
			(size 0.59 0.64)
			(layers "B.Cu" "B.Mask" "B.Paste")
			(roundrect_rratio 0.25)
			(net 252 "/Edge connector/DBP_PREQ_N")
			(pintype "passive")
		)
	)
	(footprint "antmicro-footprints:R_0402_1005Metric"
		(layer "B.Cu")
		(at 117.495 149.675)
		(descr "Resistor SMD 0402")
		(tags "resistor SMD 0402")
		(property "Reference" "R104"
			(at 0.805 0.425 0)
			(layer "B.SilkS")
			(effects
				(font
					(size 0.7 0.7)
					(thickness 0.15)
				)
				(justify right bottom mirror)
			)
		)
		(property "Value" "R_0R_0402"
			(at 0 -1.4 0)
			(layer "B.Fab")
			(effects
				(font
					(size 0.7 0.7)
					(thickness 0.15)
				)
				(justify right bottom mirror)
			)
		)
		(property "Datasheet" "https://industrial.panasonic.com/cdbs/www-data/pdf/RDA0000/AOA0000C301.pdf"
			(at 0 0 0)
			(layer "F.Fab")
			(hide yes)
			(effects
				(font
					(size 1.27 1.27)
					(thickness 0.15)
				)
			)
		)
		(property "Description" "SMD Chip Resistor, Jumper, 0 ohm, 100 mW, 0402 [1005 Metric], Thick Film, General Purpose"
			(at 0 0 0)
			(layer "F.Fab")
			(hide yes)
			(effects
				(font
					(size 1.27 1.27)
					(thickness 0.15)
				)
			)
		)
		(property "Author" "Antmicro"
			(at 0 0 0)
			(layer "B.Fab")
			(hide yes)
			(effects
				(font
					(size 1 1)
					(thickness 0.15)
				)
				(justify mirror)
			)
		)
		(property "Current" "1A"
			(at 0 0 0)
			(layer "B.Fab")
			(hide yes)
			(effects
				(font
					(size 1 1)
					(thickness 0.15)
				)
				(justify mirror)
			)
		)
		(property "License" "Apache-2.0"
			(at 0 0 0)
			(layer "B.Fab")
			(hide yes)
			(effects
				(font
					(size 1 1)
					(thickness 0.15)
				)
				(justify mirror)
			)
		)
		(property "MPN" "ERJ2GE0R00X"
			(at 0 0 0)
			(layer "B.Fab")
			(hide yes)
			(effects
				(font
					(size 1 1)
					(thickness 0.15)
				)
				(justify mirror)
			)
		)
		(property "Manufacturer" "Panasonic"
			(at 0 0 0)
			(layer "B.Fab")
			(hide yes)
			(effects
				(font
					(size 1 1)
					(thickness 0.15)
				)
				(justify mirror)
			)
		)
		(property "Tolerance" "~"
			(at 0 0 0)
			(layer "B.Fab")
			(hide yes)
			(effects
				(font
					(size 1 1)
					(thickness 0.15)
				)
				(justify mirror)
			)
		)
		(property "Val" "0R"
			(at 0 0 0)
			(layer "B.Fab")
			(hide yes)
			(effects
				(font
					(size 1 1)
					(thickness 0.15)
				)
				(justify mirror)
			)
		)
		(sheetname "/Edge connector/")
		(sheetfile "edge-connector.kicad_sch")
		(attr smd)
		(fp_rect
			(start -0.925 0.47)
			(end 0.925 -0.47)
			(stroke
				(width 0.05)
				(type default)
			)
			(fill no)
			(layer "B.CrtYd")
		)
		(fp_rect
			(start -0.5 0.25)
			(end 0.5 -0.25)
			(stroke
				(width 0.15)
				(type solid)
			)
			(fill no)
			(layer "B.Fab")
		)
		(pad "1" smd roundrect
			(at -0.48 0)
			(size 0.59 0.64)
			(layers "B.Cu" "B.Mask" "B.Paste")
			(roundrect_rratio 0.25)
			(net 390 "SYS_PWROK_R")
			(pintype "passive")
		)
		(pad "2" smd roundrect
			(at 0.48 0)
			(size 0.59 0.64)
			(layers "B.Cu" "B.Mask" "B.Paste")
			(roundrect_rratio 0.25)
			(net 253 "/Edge connector/SYS_PWROK")
			(pintype "passive")
		)
	)
	(footprint "antmicro-footprints:C_0402_1005Metric"
		(layer "B.Cu")
		(at 133.35 90.8125 180)
		(descr "Capacitor SMD 0402")
		(tags "capacitor SMD 0402")
		(property "Reference" "C135"
			(at 0.75 -0.3875 0)
			(layer "B.SilkS")
			(effects
				(font
					(size 0.7 0.7)
					(thickness 0.15)
				)
				(justify left bottom mirror)
			)
		)
		(property "Value" "C_100n_0402"
			(at 0 -1.4 0)
			(layer "B.Fab")
			(effects
				(font
					(size 0.7 0.7)
					(thickness 0.15)
				)
				(justify left bottom mirror)
			)
		)
		(property "Datasheet" "https://www.murata.com/products/productdetail?partno=GRM155R61H104KE14%23"
			(at 0 0 180)
			(layer "F.Fab")
			(hide yes)
			(effects
				(font
					(size 1.27 1.27)
					(thickness 0.15)
				)
			)
		)
		(property "Description" "SMD Multilayer Ceramic Capacitor, 0.1 µF, 50 V, 0402 [1005 Metric], ± 10%, X5R, GRM Series"
			(at 0 0 180)
			(layer "F.Fab")
			(hide yes)
			(effects
				(font
					(size 1.27 1.27)
					(thickness 0.15)
				)
			)
		)
		(property "Author" "Antmicro"
			(at 266.7 181.625 0)
			(layer "B.Fab")
			(hide yes)
			(effects
				(font
					(size 1 1)
					(thickness 0.15)
				)
				(justify mirror)
			)
		)
		(property "Dielectric" "X5R"
			(at 266.7 181.625 0)
			(layer "B.Fab")
			(hide yes)
			(effects
				(font
					(size 1 1)
					(thickness 0.15)
				)
				(justify mirror)
			)
		)
		(property "License" "Apache-2.0"
			(at 266.7 181.625 0)
			(layer "B.Fab")
			(hide yes)
			(effects
				(font
					(size 1 1)
					(thickness 0.15)
				)
				(justify mirror)
			)
		)
		(property "MPN" "GRM155R61H104KE14D"
			(at 266.7 181.625 0)
			(layer "B.Fab")
			(hide yes)
			(effects
				(font
					(size 1 1)
					(thickness 0.15)
				)
				(justify mirror)
			)
		)
		(property "Manufacturer" "Murata"
			(at 266.7 181.625 0)
			(layer "B.Fab")
			(hide yes)
			(effects
				(font
					(size 1 1)
					(thickness 0.15)
				)
				(justify mirror)
			)
		)
		(property "Val" "100n"
			(at 266.7 181.625 0)
			(layer "B.Fab")
			(hide yes)
			(effects
				(font
					(size 1 1)
					(thickness 0.15)
				)
				(justify mirror)
			)
		)
		(property "Voltage" "50V"
			(at 266.7 181.625 0)
			(layer "B.Fab")
			(hide yes)
			(effects
				(font
					(size 1 1)
					(thickness 0.15)
				)
				(justify mirror)
			)
		)
		(sheetname "/Interfaces/")
		(sheetfile "interfaces.kicad_sch")
		(attr smd)
		(fp_rect
			(start -0.925 0.47)
			(end 0.925 -0.47)
			(stroke
				(width 0.05)
				(type default)
			)
			(fill no)
			(layer "B.CrtYd")
		)
		(fp_line
			(start 0.504 0.25)
			(end 0.504 -0.248)
			(stroke
				(width 0.15)
				(type solid)
			)
			(layer "B.Fab")
		)
		(fp_line
			(start 0.504 -0.248)
			(end -0.494 -0.248)
			(stroke
				(width 0.15)
				(type solid)
			)
			(layer "B.Fab")
		)
		(fp_line
			(start -0.494 0.25)
			(end 0.504 0.25)
			(stroke
				(width 0.15)
				(type solid)
			)
			(layer "B.Fab")
		)
		(fp_line
			(start -0.494 -0.248)
			(end -0.494 0.25)
			(stroke
				(width 0.15)
				(type solid)
			)
			(layer "B.Fab")
		)
		(pad "1" smd roundrect
			(at -0.48 0 180)
			(size 0.59 0.64)
			(layers "B.Cu" "B.Mask" "B.Paste")
			(roundrect_rratio 0.25)
			(net 1 "GND")
			(pintype "passive")
		)
		(pad "2" smd roundrect
			(at 0.48 0 180)
			(size 0.59 0.64)
			(layers "B.Cu" "B.Mask" "B.Paste")
			(roundrect_rratio 0.25)
			(net 597 "1V8_FT")
			(pintype "passive")
		)
	)
	(footprint "antmicro-footprints:C_0402_1005Metric"
		(layer "B.Cu")
		(at 136.85 88.9125 -90)
		(descr "Capacitor SMD 0402")
		(tags "capacitor SMD 0402")
		(property "Reference" "C139"
			(at 0.7875 -0.35 90)
			(layer "B.SilkS")
			(effects
				(font
					(size 0.7 0.7)
					(thickness 0.15)
				)
				(justify left bottom mirror)
			)
		)
		(property "Value" "C_100n_0402"
			(at 0 -1.4 90)
			(layer "B.Fab")
			(effects
				(font
					(size 0.7 0.7)
					(thickness 0.15)
				)
				(justify left bottom mirror)
			)
		)
		(property "Datasheet" "https://www.murata.com/products/productdetail?partno=GRM155R61H104KE14%23"
			(at 0 0 270)
			(layer "F.Fab")
			(hide yes)
			(effects
				(font
					(size 1.27 1.27)
					(thickness 0.15)
				)
			)
		)
		(property "Description" "SMD Multilayer Ceramic Capacitor, 0.1 µF, 50 V, 0402 [1005 Metric], ± 10%, X5R, GRM Series"
			(at 0 0 270)
			(layer "F.Fab")
			(hide yes)
			(effects
				(font
					(size 1.27 1.27)
					(thickness 0.15)
				)
			)
		)
		(property "Author" "Antmicro"
			(at 47.9375 225.7625 0)
			(layer "B.Fab")
			(hide yes)
			(effects
				(font
					(size 1 1)
					(thickness 0.15)
				)
				(justify mirror)
			)
		)
		(property "Dielectric" "X5R"
			(at 47.9375 225.7625 0)
			(layer "B.Fab")
			(hide yes)
			(effects
				(font
					(size 1 1)
					(thickness 0.15)
				)
				(justify mirror)
			)
		)
		(property "License" "Apache-2.0"
			(at 47.9375 225.7625 0)
			(layer "B.Fab")
			(hide yes)
			(effects
				(font
					(size 1 1)
					(thickness 0.15)
				)
				(justify mirror)
			)
		)
		(property "MPN" "GRM155R61H104KE14D"
			(at 47.9375 225.7625 0)
			(layer "B.Fab")
			(hide yes)
			(effects
				(font
					(size 1 1)
					(thickness 0.15)
				)
				(justify mirror)
			)
		)
		(property "Manufacturer" "Murata"
			(at 47.9375 225.7625 0)
			(layer "B.Fab")
			(hide yes)
			(effects
				(font
					(size 1 1)
					(thickness 0.15)
				)
				(justify mirror)
			)
		)
		(property "Val" "100n"
			(at 47.9375 225.7625 0)
			(layer "B.Fab")
			(hide yes)
			(effects
				(font
					(size 1 1)
					(thickness 0.15)
				)
				(justify mirror)
			)
		)
		(property "Voltage" "50V"
			(at 47.9375 225.7625 0)
			(layer "B.Fab")
			(hide yes)
			(effects
				(font
					(size 1 1)
					(thickness 0.15)
				)
				(justify mirror)
			)
		)
		(sheetname "/Interfaces/")
		(sheetfile "interfaces.kicad_sch")
		(attr smd)
		(fp_rect
			(start -0.925 0.47)
			(end 0.925 -0.47)
			(stroke
				(width 0.05)
				(type default)
			)
			(fill no)
			(layer "B.CrtYd")
		)
		(fp_line
			(start -0.494 0.25)
			(end 0.504 0.25)
			(stroke
				(width 0.15)
				(type solid)
			)
			(layer "B.Fab")
		)
		(fp_line
			(start 0.504 0.25)
			(end 0.504 -0.248)
			(stroke
				(width 0.15)
				(type solid)
			)
			(layer "B.Fab")
		)
		(fp_line
			(start -0.494 -0.248)
			(end -0.494 0.25)
			(stroke
				(width 0.15)
				(type solid)
			)
			(layer "B.Fab")
		)
		(fp_line
			(start 0.504 -0.248)
			(end -0.494 -0.248)
			(stroke
				(width 0.15)
				(type solid)
			)
			(layer "B.Fab")
		)
		(pad "1" smd roundrect
			(at -0.48 0 270)
			(size 0.59 0.64)
			(layers "B.Cu" "B.Mask" "B.Paste")
			(roundrect_rratio 0.25)
			(net 1 "GND")
			(pintype "passive")
		)
		(pad "2" smd roundrect
			(at 0.48 0 270)
			(size 0.59 0.64)
			(layers "B.Cu" "B.Mask" "B.Paste")
			(roundrect_rratio 0.25)
			(net 115 "/Interfaces/FT_VPHY")
			(pintype "passive")
		)
	)
	(footprint "antmicro-footprints:C_0402_1005Metric"
		(layer "B.Cu")
		(at 137.85 88.9125 -90)
		(descr "Capacitor SMD 0402")
		(tags "capacitor SMD 0402")
		(property "Reference" "C162"
			(at 0.7875 -0.35 90)
			(layer "B.SilkS")
			(effects
				(font
					(size 0.7 0.7)
					(thickness 0.15)
				)
				(justify left bottom mirror)
			)
		)
		(property "Value" "C_4u7_0402"
			(at 0 -1.4 90)
			(layer "B.Fab")
			(effects
				(font
					(size 0.7 0.7)
					(thickness 0.15)
				)
				(justify left bottom mirror)
			)
		)
		(property "Datasheet" "https://www.murata.com/products/productdetail?partno=GRM155R61A475MEAA%23"
			(at 0 0 270)
			(layer "F.Fab")
			(hide yes)
			(effects
				(font
					(size 1.27 1.27)
					(thickness 0.15)
				)
			)
		)
		(property "Description" "SMD Multilayer Ceramic Capacitor, 4.7 µF, 10 V, 0402 [1005 Metric], ± 20%, X5R, GRM Series"
			(at 0 0 270)
			(layer "F.Fab")
			(hide yes)
			(effects
				(font
					(size 1.27 1.27)
					(thickness 0.15)
				)
			)
		)
		(property "Author" "Antmicro"
			(at 48.9375 226.7625 0)
			(layer "B.Fab")
			(hide yes)
			(effects
				(font
					(size 1 1)
					(thickness 0.15)
				)
				(justify mirror)
			)
		)
		(property "Dielectric" ""
			(at 48.9375 226.7625 0)
			(layer "B.Fab")
			(hide yes)
			(effects
				(font
					(size 1 1)
					(thickness 0.15)
				)
				(justify mirror)
			)
		)
		(property "License" "Apache-2.0"
			(at 48.9375 226.7625 0)
			(layer "B.Fab")
			(hide yes)
			(effects
				(font
					(size 1 1)
					(thickness 0.15)
				)
				(justify mirror)
			)
		)
		(property "MPN" "GRM155R61A475MEAAD"
			(at 48.9375 226.7625 0)
			(layer "B.Fab")
			(hide yes)
			(effects
				(font
					(size 1 1)
					(thickness 0.15)
				)
				(justify mirror)
			)
		)
		(property "Manufacturer" "Murata"
			(at 48.9375 226.7625 0)
			(layer "B.Fab")
			(hide yes)
			(effects
				(font
					(size 1 1)
					(thickness 0.15)
				)
				(justify mirror)
			)
		)
		(property "Val" "4u7"
			(at 48.9375 226.7625 0)
			(layer "B.Fab")
			(hide yes)
			(effects
				(font
					(size 1 1)
					(thickness 0.15)
				)
				(justify mirror)
			)
		)
		(property "Voltage" ""
			(at 48.9375 226.7625 0)
			(layer "B.Fab")
			(hide yes)
			(effects
				(font
					(size 1 1)
					(thickness 0.15)
				)
				(justify mirror)
			)
		)
		(sheetname "/Interfaces/")
		(sheetfile "interfaces.kicad_sch")
		(attr smd)
		(fp_rect
			(start -0.925 0.47)
			(end 0.925 -0.47)
			(stroke
				(width 0.05)
				(type default)
			)
			(fill no)
			(layer "B.CrtYd")
		)
		(fp_line
			(start -0.494 0.25)
			(end 0.504 0.25)
			(stroke
				(width 0.15)
				(type solid)
			)
			(layer "B.Fab")
		)
		(fp_line
			(start 0.504 0.25)
			(end 0.504 -0.248)
			(stroke
				(width 0.15)
				(type solid)
			)
			(layer "B.Fab")
		)
		(fp_line
			(start -0.494 -0.248)
			(end -0.494 0.25)
			(stroke
				(width 0.15)
				(type solid)
			)
			(layer "B.Fab")
		)
		(fp_line
			(start 0.504 -0.248)
			(end -0.494 -0.248)
			(stroke
				(width 0.15)
				(type solid)
			)
			(layer "B.Fab")
		)
		(pad "1" smd roundrect
			(at -0.48 0 270)
			(size 0.59 0.64)
			(layers "B.Cu" "B.Mask" "B.Paste")
			(roundrect_rratio 0.25)
			(net 1 "GND")
			(pintype "passive")
		)
		(pad "2" smd roundrect
			(at 0.48 0 270)
			(size 0.59 0.64)
			(layers "B.Cu" "B.Mask" "B.Paste")
			(roundrect_rratio 0.25)
			(net 115 "/Interfaces/FT_VPHY")
			(pintype "passive")
		)
	)
	(footprint "antmicro-footprints:FB_0402_1005Metric"
		(layer "B.Cu")
		(at 139.35 89.4125 180)
		(descr "Ferrite Bead SMD 0402")
		(tags "ferrite bead SMD 0402")
		(property "Reference" "FB2"
			(at -1.05 0.5125 0)
			(layer "B.SilkS")
			(effects
				(font
					(size 0.7 0.7)
					(thickness 0.15)
				)
				(justify left bottom mirror)
			)
		)
		(property "Value" "FB_600Z_0.3A_Murata-BLM15AG_0402"
			(at 0 -1.4 0)
			(layer "B.Fab")
			(effects
				(font
					(size 0.7 0.7)
					(thickness 0.15)
				)
				(justify left bottom mirror)
			)
		)
		(property "Datasheet" "https://www.murata.com/en-us/products/productdata/8796740059166/ENFA0018.pdf"
			(at 0 0 180)
			(layer "F.Fab")
			(hide yes)
			(effects
				(font
					(size 1.27 1.27)
					(thickness 0.15)
				)
			)
		)
		(property "Description" "Ferrite Bead, 0402 [1005 Metric], 600 ohm, 300 mA, BLM15AG_SN, 0.6 ohm, ± 25%, General use"
			(at 0 0 180)
			(layer "F.Fab")
			(hide yes)
			(effects
				(font
					(size 1.27 1.27)
					(thickness 0.15)
				)
			)
		)
		(property "Author" "Antmicro"
			(at 278.7 178.825 0)
			(layer "B.Fab")
			(hide yes)
			(effects
				(font
					(size 1 1)
					(thickness 0.15)
				)
				(justify mirror)
			)
		)
		(property "Current" ""
			(at 278.7 178.825 0)
			(layer "B.Fab")
			(hide yes)
			(effects
				(font
					(size 1 1)
					(thickness 0.15)
				)
				(justify mirror)
			)
		)
		(property "License" "Apache-2.0"
			(at 278.7 178.825 0)
			(layer "B.Fab")
			(hide yes)
			(effects
				(font
					(size 1 1)
					(thickness 0.15)
				)
				(justify mirror)
			)
		)
		(property "MPN" "BLM15AG601SN1D"
			(at 278.7 178.825 0)
			(layer "B.Fab")
			(hide yes)
			(effects
				(font
					(size 1 1)
					(thickness 0.15)
				)
				(justify mirror)
			)
		)
		(property "Manufacturer" "Murata"
			(at 278.7 178.825 0)
			(layer "B.Fab")
			(hide yes)
			(effects
				(font
					(size 1 1)
					(thickness 0.15)
				)
				(justify mirror)
			)
		)
		(property "Val" "600Z/0.3A"
			(at 278.7 178.825 0)
			(layer "B.Fab")
			(hide yes)
			(effects
				(font
					(size 1 1)
					(thickness 0.15)
				)
				(justify mirror)
			)
		)
		(sheetname "/Interfaces/")
		(sheetfile "interfaces.kicad_sch")
		(attr smd)
		(fp_rect
			(start -0.925 0.47)
			(end 0.925 -0.47)
			(stroke
				(width 0.05)
				(type default)
			)
			(fill no)
			(layer "B.CrtYd")
		)
		(fp_rect
			(start -0.5 0.25)
			(end 0.5 -0.25)
			(stroke
				(width 0.15)
				(type solid)
			)
			(fill no)
			(layer "B.Fab")
		)
		(pad "1" smd roundrect
			(at -0.48 0 180)
			(size 0.59 0.64)
			(layers "B.Cu" "B.Mask" "B.Paste")
			(roundrect_rratio 0.25)
			(net 2 "VCC3V3")
			(pintype "passive")
		)
		(pad "2" smd roundrect
			(at 0.48 0 180)
			(size 0.59 0.64)
			(layers "B.Cu" "B.Mask" "B.Paste")
			(roundrect_rratio 0.25)
			(net 115 "/Interfaces/FT_VPHY")
			(pintype "passive")
		)
	)
)
